(kicad_pcb
	(version 20260206)
	(generator "pcbnew")
	(generator_version "10.0")
	(general
		(thickness 1.6)
		(legacy_teardrops no)
	)
	(paper "A4")
	(title_block
		(title "v1-chassis-manager — T6M_CM_d_v01_1031_1645.brd")
		(comment 1 "Open CloudServer (Microsoft) / footprints 1738-1745 of 2512")
	)
	(layers
		(0 "F.Cu" signal "TOP")
		(4 "In1.Cu" signal "GND1")
		(6 "In2.Cu" signal "IN1")
		(8 "In3.Cu" signal "VCC1")
		(10 "In4.Cu" signal "VCC2")
		(12 "In5.Cu" signal "GND2")
		(14 "In6.Cu" signal "IN2")
		(16 "In7.Cu" signal "IN3")
		(18 "In8.Cu" signal "GND3")
		(2 "B.Cu" signal "BOTTOM")
		(9 "F.Adhes" user "F.Adhesive")
		(11 "B.Adhes" user "B.Adhesive")
		(13 "F.Paste" user "Package Geometry/Pastemask Top")
		(15 "B.Paste" user "Package Geometry/Pastemask Bottom")
		(5 "F.SilkS" user "Ref Des/Silkscreen Top")
		(7 "B.SilkS" user "Ref Des/Silkscreen Bottom")
		(1 "F.Mask" user "Board Geometry/Soldermask Top")
		(3 "B.Mask" user "Board Geometry/Soldermask Bottom")
		(17 "Dwgs.User" user "User.Drawings")
		(19 "Cmts.User" user "User.Comments")
		(21 "Eco1.User" user "User.Eco1")
		(23 "Eco2.User" user "User.Eco2")
		(25 "Edge.Cuts" user "Board Geometry/Outline")
		(27 "Margin" user)
		(31 "F.CrtYd" user "Package Geometry/Place Bound Top")
		(29 "B.CrtYd" user "Package Geometry/Place Bound Bottom")
		(35 "F.Fab" user "Ref Des/Assembly Top")
		(33 "B.Fab" user "Ref Des/Assembly Bottom")
	)
	(footprint ""
		(layer "B.Cu")
		(at 148.06676 -173.521624 -90)
		(property "Reference" "U66"
			(at -5.82295 2.102612 0)
			(unlocked yes)
			(layer "B.SilkS")
			(effects
				(font
					(size 0.7874 0.5842)
					(thickness 0.1524)
				)
				(justify left mirror)
			)
		)
		(property "Value" ""
			(at 0 0 90)
			(layer "B.Fab")
			(effects
				(font
					(size 1.27 1.27)
				)
				(justify mirror)
			)
		)
		(duplicate_pad_numbers_are_jumpers no)
		(fp_line
			(start -3.9624 2.0066)
			(end 3.9624 2.0066)
			(stroke
				(width 0.1524)
				(type default)
			)
			(layer "B.SilkS")
		)
		(fp_line
			(start 3.9624 2.0066)
			(end 3.9624 0.5842)
			(stroke
				(width 0.1524)
				(type default)
			)
			(layer "B.SilkS")
		)
		(fp_line
			(start 3.9624 0.5842)
			(end 3.3782 0)
			(stroke
				(width 0.1524)
				(type default)
			)
			(layer "B.SilkS")
		)
		(fp_line
			(start 3.3782 0)
			(end 3.9624 -0.5842)
			(stroke
				(width 0.1524)
				(type default)
			)
			(layer "B.SilkS")
		)
		(fp_line
			(start 3.9624 -0.5842)
			(end 3.9624 -2.0066)
			(stroke
				(width 0.1524)
				(type default)
			)
			(layer "B.SilkS")
		)
		(fp_line
			(start -3.9624 -2.0066)
			(end -3.9624 2.0066)
			(stroke
				(width 0.1524)
				(type default)
			)
			(layer "B.SilkS")
		)
		(fp_line
			(start 3.9624 -2.0066)
			(end -3.9624 -2.0066)
			(stroke
				(width 0.1524)
				(type default)
			)
			(layer "B.SilkS")
		)
		(fp_circle
			(center 3.429 1.524)
			(end 3.429 1.27)
			(stroke
				(width 0.1524)
				(type default)
			)
			(fill no)
			(layer "B.SilkS")
		)
		(fp_poly
			(pts
				(xy 3.962654 3.6703) (xy 3.974846 -3.6703) (xy -3.9624 -3.6703) (xy -3.9624 3.6703)
			)
			(stroke
				(width 0)
				(type default)
			)
			(fill no)
			(layer "B.CrtYd")
		)
		(pad "1" smd rect
			(at 3.57505 2.921 90)
			(size 0.3556 1.4986)
			(layers "B.Cu" "B.Mask" "B.Paste")
			(net "N21700156")
		)
		(pad "2" smd rect
			(at 2.925064 2.921 90)
			(size 0.3556 1.4986)
			(layers "B.Cu" "B.Mask" "B.Paste")
			(net "N21698757")
		)
		(pad "3" smd rect
			(at 2.275078 2.921 90)
			(size 0.3556 1.4986)
			(layers "B.Cu" "B.Mask" "B.Paste")
			(net "N21698959")
		)
		(pad "4" smd rect
			(at 1.625092 2.921 90)
			(size 0.3556 1.4986)
			(layers "B.Cu" "B.Mask" "B.Paste")
			(net "T9_NODE1_EN")
		)
		(pad "5" smd rect
			(at 0.975106 2.921 90)
			(size 0.3556 1.4986)
			(layers "B.Cu" "B.Mask" "B.Paste")
			(net "T9_NODE2_EN")
		)
		(pad "6" smd rect
			(at 0.32512 2.921 90)
			(size 0.3556 1.4986)
			(layers "B.Cu" "B.Mask" "B.Paste")
			(net "T9_NODE3_EN")
		)
		(pad "7" smd rect
			(at -0.32512 2.921 90)
			(size 0.3556 1.4986)
			(layers "B.Cu" "B.Mask" "B.Paste")
			(net "T9_NODE4_EN")
		)
		(pad "8" smd rect
			(at -0.975106 2.921 90)
			(size 0.3556 1.4986)
			(layers "B.Cu" "B.Mask" "B.Paste")
			(net "T10_NODE1_EN")
		)
		(pad "9" smd rect
			(at -1.625092 2.921 90)
			(size 0.3556 1.4986)
			(layers "B.Cu" "B.Mask" "B.Paste")
			(net "T10_NODE2_EN")
		)
		(pad "10" smd rect
			(at -2.275078 2.921 90)
			(size 0.3556 1.4986)
			(layers "B.Cu" "B.Mask" "B.Paste")
			(net "T10_NODE3_EN")
		)
		(pad "11" smd rect
			(at -2.925064 2.921 90)
			(size 0.3556 1.4986)
			(layers "B.Cu" "B.Mask" "B.Paste")
			(net "T10_NODE4_EN")
		)
		(pad "12" smd rect
			(at -3.57505 2.921 90)
			(size 0.3556 1.4986)
			(layers "B.Cu" "B.Mask" "B.Paste")
			(net "GND")
		)
		(pad "13" smd rect
			(at -3.57505 -2.921 90)
			(size 0.3556 1.4986)
			(layers "B.Cu" "B.Mask" "B.Paste")
			(net "T11_NODE1_EN")
		)
		(pad "14" smd rect
			(at -2.925064 -2.921 90)
			(size 0.3556 1.4986)
			(layers "B.Cu" "B.Mask" "B.Paste")
			(net "T11_NODE2_EN")
		)
		(pad "15" smd rect
			(at -2.275078 -2.921 90)
			(size 0.3556 1.4986)
			(layers "B.Cu" "B.Mask" "B.Paste")
			(net "T11_NODE3_EN")
		)
		(pad "16" smd rect
			(at -1.625092 -2.921 90)
			(size 0.3556 1.4986)
			(layers "B.Cu" "B.Mask" "B.Paste")
			(net "T11_NODE4_EN")
		)
		(pad "17" smd rect
			(at -0.975106 -2.921 90)
			(size 0.3556 1.4986)
			(layers "B.Cu" "B.Mask" "B.Paste")
			(net "T12_NODE1_EN")
		)
		(pad "18" smd rect
			(at -0.32512 -2.921 90)
			(size 0.3556 1.4986)
			(layers "B.Cu" "B.Mask" "B.Paste")
			(net "T12_NODE2_EN")
		)
		(pad "19" smd rect
			(at 0.32512 -2.921 90)
			(size 0.3556 1.4986)
			(layers "B.Cu" "B.Mask" "B.Paste")
			(net "T12_NODE3_EN")
		)
		(pad "20" smd rect
			(at 0.975106 -2.921 90)
			(size 0.3556 1.4986)
			(layers "B.Cu" "B.Mask" "B.Paste")
			(net "T12_NODE4_EN")
		)
		(pad "21" smd rect
			(at 1.625092 -2.921 90)
			(size 0.3556 1.4986)
			(layers "B.Cu" "B.Mask" "B.Paste")
			(net "N21698959")
		)
		(pad "22" smd rect
			(at 2.275078 -2.921 90)
			(size 0.3556 1.4986)
			(layers "B.Cu" "B.Mask" "B.Paste")
			(net "I2C_COM3_SCL")
		)
		(pad "23" smd rect
			(at 2.925064 -2.921 90)
			(size 0.3556 1.4986)
			(layers "B.Cu" "B.Mask" "B.Paste")
			(net "I2C_COM3_SDA")
		)
		(pad "24" smd rect
			(at 3.57505 -2.921 90)
			(size 0.3556 1.4986)
			(layers "B.Cu" "B.Mask" "B.Paste")
			(net "P3V3_NODE1")
		)
	)
	(footprint ""
		(layer "B.Cu")
		(at 73.791318 -77.94625)
		(property "Reference" "R117"
			(at 0.861822 1.504188 0)
			(unlocked yes)
			(layer "B.SilkS")
			(effects
				(font
					(size 0.7874 0.5842)
					(thickness 0.1524)
				)
				(justify left mirror)
			)
		)
		(property "Value" ""
			(at 0 0 0)
			(layer "B.Fab")
			(effects
				(font
					(size 1.27 1.27)
				)
				(justify mirror)
			)
		)
		(duplicate_pad_numbers_are_jumpers no)
		(fp_line
			(start -0.7874 -0.4064)
			(end -0.7874 0.4064)
			(stroke
				(width 0.1524)
				(type default)
			)
			(layer "B.SilkS")
		)
		(fp_line
			(start -0.7874 0.4064)
			(end 0.7874 0.4064)
			(stroke
				(width 0.1524)
				(type default)
			)
			(layer "B.SilkS")
		)
		(fp_line
			(start 0.7874 -0.4064)
			(end -0.7874 -0.4064)
			(stroke
				(width 0.1524)
				(type default)
			)
			(layer "B.SilkS")
		)
		(fp_line
			(start 0.7874 0.4064)
			(end 0.7874 -0.4064)
			(stroke
				(width 0.1524)
				(type default)
			)
			(layer "B.SilkS")
		)
		(fp_poly
			(pts
				(xy 0.508 0.2794) (xy 0.508 0.2286) (xy 0.635 0.2286) (xy 0.635 -0.254) (xy 0.5334 -0.254) (xy 0.5334 -0.2794)
				(xy -0.5334 -0.2794) (xy -0.5334 -0.254) (xy -0.635 -0.254) (xy -0.635 0.254) (xy -0.5334 0.254)
				(xy -0.5334 0.2794)
			)
			(stroke
				(width 0)
				(type default)
			)
			(fill no)
			(layer "B.CrtYd")
		)
		(pad "1" smd rect
			(at -0.40005 0 180)
			(size 0.4572 0.508)
			(layers "B.Cu" "B.Mask" "B.Paste")
			(net "SVID_CPU_NODE1_PVCCP_DAT_R")
		)
		(pad "2" smd rect
			(at 0.40005 0 180)
			(size 0.4572 0.508)
			(layers "B.Cu" "B.Mask" "B.Paste")
			(net "SVID_CPU_NODE1_PVCCP_DAT")
		)
	)
	(footprint ""
		(layer "B.Cu")
		(at 110.44936 -180.633624 180)
		(property "Reference" "R716"
			(at 21.356828 -32.269176 0)
			(unlocked yes)
			(layer "B.SilkS")
			(effects
				(font
					(size 0.7874 0.5842)
					(thickness 0.1524)
				)
				(justify left mirror)
			)
		)
		(property "Value" ""
			(at 0 0 0)
			(layer "B.Fab")
			(effects
				(font
					(size 1.27 1.27)
				)
				(justify mirror)
			)
		)
		(duplicate_pad_numbers_are_jumpers no)
		(fp_line
			(start 0.7874 0.4064)
			(end 0.7874 -0.4064)
			(stroke
				(width 0.1524)
				(type default)
			)
			(layer "B.SilkS")
		)
		(fp_line
			(start 0.7874 -0.4064)
			(end -0.7874 -0.4064)
			(stroke
				(width 0.1524)
				(type default)
			)
			(layer "B.SilkS")
		)
		(fp_line
			(start -0.7874 0.4064)
			(end 0.7874 0.4064)
			(stroke
				(width 0.1524)
				(type default)
			)
			(layer "B.SilkS")
		)
		(fp_line
			(start -0.7874 -0.4064)
			(end -0.7874 0.4064)
			(stroke
				(width 0.1524)
				(type default)
			)
			(layer "B.SilkS")
		)
		(fp_poly
			(pts
				(xy 0.508 0.2794) (xy 0.508 0.2286) (xy 0.635 0.2286) (xy 0.635 -0.254) (xy 0.5334 -0.254) (xy 0.5334 -0.2794)
				(xy -0.5334 -0.2794) (xy -0.5334 -0.254) (xy -0.635 -0.254) (xy -0.635 0.254) (xy -0.5334 0.254)
				(xy -0.5334 0.2794)
			)
			(stroke
				(width 0)
				(type default)
			)
			(fill no)
			(layer "B.CrtYd")
		)
		(pad "1" smd rect
			(at -0.40005 0)
			(size 0.4572 0.508)
			(layers "B.Cu" "B.Mask" "B.Paste")
			(net "T6_NODE3_EN")
		)
		(pad "2" smd rect
			(at 0.40005 0)
			(size 0.4572 0.508)
			(layers "B.Cu" "B.Mask" "B.Paste")
			(net "P5V_NODE1")
		)
	)
	(footprint ""
		(layer "B.Cu")
		(at 37.92474 -146.58467)
		(property "Reference" "R552"
			(at -2.549652 0.339852 0)
			(unlocked yes)
			(layer "B.SilkS")
			(effects
				(font
					(size 0.7874 0.5842)
					(thickness 0.1524)
				)
				(justify left mirror)
			)
		)
		(property "Value" ""
			(at 0 0 0)
			(layer "B.Fab")
			(effects
				(font
					(size 1.27 1.27)
				)
				(justify mirror)
			)
		)
		(duplicate_pad_numbers_are_jumpers no)
		(fp_line
			(start -0.7874 -0.4064)
			(end -0.7874 0.4064)
			(stroke
				(width 0.1524)
				(type default)
			)
			(layer "B.SilkS")
		)
		(fp_line
			(start -0.7874 0.4064)
			(end 0.7874 0.4064)
			(stroke
				(width 0.1524)
				(type default)
			)
			(layer "B.SilkS")
		)
		(fp_line
			(start 0.7874 -0.4064)
			(end -0.7874 -0.4064)
			(stroke
				(width 0.1524)
				(type default)
			)
			(layer "B.SilkS")
		)
		(fp_line
			(start 0.7874 0.4064)
			(end 0.7874 -0.4064)
			(stroke
				(width 0.1524)
				(type default)
			)
			(layer "B.SilkS")
		)
		(fp_poly
			(pts
				(xy 0.508 0.2794) (xy 0.508 0.2286) (xy 0.635 0.2286) (xy 0.635 -0.254) (xy 0.5334 -0.254) (xy 0.5334 -0.2794)
				(xy -0.5334 -0.2794) (xy -0.5334 -0.254) (xy -0.635 -0.254) (xy -0.635 0.254) (xy -0.5334 0.254)
				(xy -0.5334 0.2794)
			)
			(stroke
				(width 0)
				(type default)
			)
			(fill no)
			(layer "B.CrtYd")
		)
		(pad "1" smd rect
			(at -0.40005 0 180)
			(size 0.4572 0.508)
			(layers "B.Cu" "B.Mask" "B.Paste")
			(net "GND")
		)
		(pad "2" smd rect
			(at 0.40005 0 180)
			(size 0.4572 0.508)
			(layers "B.Cu" "B.Mask" "B.Paste")
			(net "LAN1_DIS_REG10")
		)
	)
	(footprint ""
		(layer "B.Cu")
		(at 42.239438 -76.301346 -90)
		(property "Reference" "C39"
			(at 0.270256 -1.176528 270)
			(unlocked yes)
			(layer "B.SilkS")
			(effects
				(font
					(size 0.7874 0.5842)
					(thickness 0.1524)
				)
				(justify mirror)
			)
		)
		(property "Value" ""
			(at 0 0 90)
			(layer "B.Fab")
			(effects
				(font
					(size 1.27 1.27)
				)
				(justify mirror)
			)
		)
		(duplicate_pad_numbers_are_jumpers no)
		(fp_line
			(start -1.2954 0.5842)
			(end 1.2954 0.5842)
			(stroke
				(width 0.1524)
				(type default)
			)
			(layer "B.SilkS")
		)
		(fp_line
			(start 1.2954 0.5842)
			(end 1.2954 -0.5842)
			(stroke
				(width 0.1524)
				(type default)
			)
			(layer "B.SilkS")
		)
		(fp_line
			(start -1.2954 -0.5842)
			(end -1.2954 0.5842)
			(stroke
				(width 0.1524)
				(type default)
			)
			(layer "B.SilkS")
		)
		(fp_line
			(start 0 -0.5842)
			(end 0 0.5842)
			(stroke
				(width 0.1524)
				(type default)
			)
			(layer "B.SilkS")
		)
		(fp_line
			(start 1.2954 -0.5842)
			(end -1.2954 -0.5842)
			(stroke
				(width 0.1524)
				(type default)
			)
			(layer "B.SilkS")
		)
		(fp_poly
			(pts
				(xy -0.8636 -0.4572) (xy -0.8636 -0.3556) (xy -1.143 -0.3556) (xy -1.143 0.3556) (xy -0.8636 0.3556)
				(xy -0.8636 0.4572) (xy 0.8636 0.4572) (xy 0.8636 0.3556) (xy 1.143 0.3556) (xy 1.143 -0.3556) (xy 0.8636 -0.3556)
				(xy 0.8636 -0.4572)
			)
			(stroke
				(width 0)
				(type default)
			)
			(fill no)
			(layer "B.CrtYd")
		)
		(fp_line
			(start -0.884936 0.504952)
			(end 0.884936 0.504952)
			(stroke
				(width 0.1)
				(type default)
			)
			(layer "B.Fab")
		)
		(fp_line
			(start 0.884936 0.504952)
			(end 0.884936 -0.504952)
			(stroke
				(width 0.1)
				(type default)
			)
			(layer "B.Fab")
		)
		(fp_line
			(start -0.884936 -0.504952)
			(end -0.884936 0.504952)
			(stroke
				(width 0.1)
				(type default)
			)
			(layer "B.Fab")
		)
		(fp_line
			(start 0.884936 -0.504952)
			(end -0.884936 -0.504952)
			(stroke
				(width 0.1)
				(type default)
			)
			(layer "B.Fab")
		)
		(pad "1" smd rect
			(at -0.7366 0)
			(size 0.7112 0.8128)
			(layers "B.Cu" "B.Mask" "B.Paste")
			(net "P1V05_NODE1")
		)
		(pad "2" smd rect
			(at 0.7366 0)
			(size 0.7112 0.8128)
			(layers "B.Cu" "B.Mask" "B.Paste")
			(net "GND")
		)
	)
	(footprint ""
		(layer "B.Cu")
		(at 90.81262 -176.054512)
		(property "Reference" "R699"
			(at 24.902414 20.083272 0)
			(unlocked yes)
			(layer "B.SilkS")
			(effects
				(font
					(size 0.7874 0.5842)
					(thickness 0.1524)
				)
				(justify left mirror)
			)
		)
		(property "Value" ""
			(at 0 0 0)
			(layer "B.Fab")
			(effects
				(font
					(size 1.27 1.27)
				)
				(justify mirror)
			)
		)
		(duplicate_pad_numbers_are_jumpers no)
		(fp_line
			(start -0.7874 -0.4064)
			(end -0.7874 0.4064)
			(stroke
				(width 0.1524)
				(type default)
			)
			(layer "B.SilkS")
		)
		(fp_line
			(start -0.7874 0.4064)
			(end 0.7874 0.4064)
			(stroke
				(width 0.1524)
				(type default)
			)
			(layer "B.SilkS")
		)
		(fp_line
			(start 0.7874 -0.4064)
			(end -0.7874 -0.4064)
			(stroke
				(width 0.1524)
				(type default)
			)
			(layer "B.SilkS")
		)
		(fp_line
			(start 0.7874 0.4064)
			(end 0.7874 -0.4064)
			(stroke
				(width 0.1524)
				(type default)
			)
			(layer "B.SilkS")
		)
		(fp_poly
			(pts
				(xy 0.508 0.2794) (xy 0.508 0.2286) (xy 0.635 0.2286) (xy 0.635 -0.254) (xy 0.5334 -0.254) (xy 0.5334 -0.2794)
				(xy -0.5334 -0.2794) (xy -0.5334 -0.254) (xy -0.635 -0.254) (xy -0.635 0.254) (xy -0.5334 0.254)
				(xy -0.5334 0.2794)
			)
			(stroke
				(width 0)
				(type default)
			)
			(fill no)
			(layer "B.CrtYd")
		)
		(pad "1" smd rect
			(at -0.40005 0 180)
			(size 0.4572 0.508)
			(layers "B.Cu" "B.Mask" "B.Paste")
			(net "T3_NODE3_EN")
		)
		(pad "2" smd rect
			(at 0.40005 0 180)
			(size 0.4572 0.508)
			(layers "B.Cu" "B.Mask" "B.Paste")
			(net "P5V_NODE1")
		)
	)
	(footprint ""
		(layer "B.Cu")
		(at 46.83506 -146.59229 -90)
		(property "Reference" "C424"
			(at 0.576072 -1.417828 270)
			(unlocked yes)
			(layer "B.SilkS")
			(effects
				(font
					(size 0.7874 0.5842)
					(thickness 0.1524)
				)
				(justify left mirror)
			)
		)
		(property "Value" ""
			(at 0 0 90)
			(layer "B.Fab")
			(effects
				(font
					(size 1.27 1.27)
				)
				(justify mirror)
			)
		)
		(duplicate_pad_numbers_are_jumpers no)
		(fp_line
			(start -1.905 0.8636)
			(end 1.905 0.8636)
			(stroke
				(width 0.1524)
				(type default)
			)
			(layer "B.SilkS")
		)
		(fp_line
			(start 1.905 0.8636)
			(end 1.905 -0.8636)
			(stroke
				(width 0.1524)
				(type default)
			)
			(layer "B.SilkS")
		)
		(fp_line
			(start 0 0.8382)
			(end 0 -0.8382)
			(stroke
				(width 0.1524)
				(type default)
			)
			(layer "B.SilkS")
		)
		(fp_line
			(start -1.905 -0.8636)
			(end -1.905 0.8636)
			(stroke
				(width 0.1524)
				(type default)
			)
			(layer "B.SilkS")
		)
		(fp_line
			(start 1.905 -0.8636)
			(end -1.905 -0.8636)
			(stroke
				(width 0.1524)
				(type default)
			)
			(layer "B.SilkS")
		)
		(fp_rect
			(start 1.524 0.7366)
			(end -1.524 -0.7366)
			(stroke
				(width 0)
				(type default)
			)
			(fill no)
			(layer "B.CrtYd")
		)
		(pad "1" smd rect
			(at -0.94996 0 90)
			(size 1.1176 1.3716)
			(layers "B.Cu" "B.Mask" "B.Paste")
			(net "P1V05_LAN1")
		)
		(pad "2" smd rect
			(at 0.94996 0 90)
			(size 1.1176 1.3716)
			(layers "B.Cu" "B.Mask" "B.Paste")
			(net "GND")
		)
	)
	(footprint ""
		(layer "B.Cu")
		(at 56.68391 -21.495766)
		(property "Reference" "R209"
			(at 4.15163 0.153416 0)
			(unlocked yes)
			(layer "B.SilkS")
			(effects
				(font
					(size 0.7874 0.5842)
					(thickness 0.1524)
				)
				(justify left mirror)
			)
		)
		(property "Value" ""
			(at 0 0 0)
			(layer "B.Fab")
			(effects
				(font
					(size 1.27 1.27)
				)
				(justify mirror)
			)
		)
		(duplicate_pad_numbers_are_jumpers no)
		(fp_line
			(start -0.7874 -0.4064)
			(end -0.7874 0.4064)
			(stroke
				(width 0.1524)
				(type default)
			)
			(layer "B.SilkS")
		)
		(fp_line
			(start -0.7874 0.4064)
			(end 0.7874 0.4064)
			(stroke
				(width 0.1524)
				(type default)
			)
			(layer "B.SilkS")
		)
		(fp_line
			(start 0.7874 -0.4064)
			(end -0.7874 -0.4064)
			(stroke
				(width 0.1524)
				(type default)
			)
			(layer "B.SilkS")
		)
		(fp_line
			(start 0.7874 0.4064)
			(end 0.7874 -0.4064)
			(stroke
				(width 0.1524)
				(type default)
			)
			(layer "B.SilkS")
		)
		(fp_poly
			(pts
				(xy 0.508 0.2794) (xy 0.508 0.2286) (xy 0.635 0.2286) (xy 0.635 -0.254) (xy 0.5334 -0.254) (xy 0.5334 -0.2794)
				(xy -0.5334 -0.2794) (xy -0.5334 -0.254) (xy -0.635 -0.254) (xy -0.635 0.254) (xy -0.5334 0.254)
				(xy -0.5334 0.2794)
			)
			(stroke
				(width 0)
				(type default)
			)
			(fill no)
			(layer "B.CrtYd")
		)
		(pad "1" smd rect
			(at -0.40005 0 180)
			(size 0.4572 0.508)
			(layers "B.Cu" "B.Mask" "B.Paste")
			(net "GND")
		)
		(pad "2" smd rect
			(at 0.40005 0 180)
			(size 0.4572 0.508)
			(layers "B.Cu" "B.Mask" "B.Paste")
			(net "PD_NODE1_DM3")
		)
	)
)
